(kicad_pcb
	(version 20260206)
	(generator "pcbnew")
	(generator_version "10.0")
	(general
		(thickness 1.6)
		(legacy_teardrops no)
	)
	(paper "A4")
	(title_block
		(title "03242023_DA0F0TMBIJ0_F0T_Motherboard_J_brd_V01_OCP.brd")
		(comment 1 "Grand Teton / footprints 3617-3623 of 6105")
	)
	(layers
		(0 "F.Cu" signal "TOP")
		(4 "In1.Cu" signal "GND")
		(6 "In2.Cu" signal "IN1")
		(8 "In3.Cu" signal "GND1")
		(10 "In4.Cu" signal "IN2")
		(12 "In5.Cu" signal "GND2")
		(14 "In6.Cu" signal "IN3")
		(16 "In7.Cu" signal "GND3")
		(18 "In8.Cu" signal "VCC")
		(20 "In9.Cu" signal "VCC1")
		(22 "In10.Cu" signal "GND4")
		(24 "In11.Cu" signal "IN4")
		(26 "In12.Cu" signal "GND5")
		(28 "In13.Cu" signal "IN5")
		(30 "In14.Cu" signal "GND6")
		(32 "In15.Cu" signal "IN6")
		(34 "In16.Cu" signal "GND7")
		(2 "B.Cu" signal "BOTTOM")
		(9 "F.Adhes" user "F.Adhesive")
		(11 "B.Adhes" user "B.Adhesive")
		(13 "F.Paste" user "Package Geometry/Pastemask Top")
		(15 "B.Paste" user "Package Geometry/Pastemask Bottom")
		(5 "F.SilkS" user "Ref Des/Silkscreen Top")
		(7 "B.SilkS" user "Ref Des/Silkscreen Bottom")
		(1 "F.Mask" user "Board Geometry/Soldermask Top")
		(3 "B.Mask" user "Board Geometry/Soldermask Bottom")
		(17 "Dwgs.User" user "User.Drawings")
		(19 "Cmts.User" user "User.Comments")
		(21 "Eco1.User" user "User.Eco1")
		(23 "Eco2.User" user "User.Eco2")
		(25 "Edge.Cuts" user "Board Geometry/Outline")
		(27 "Margin" user)
		(31 "F.CrtYd" user "Package Geometry/Place Bound Top")
		(29 "B.CrtYd" user "Package Geometry/Place Bound Bottom")
		(35 "F.Fab" user "Ref Des/Assembly Top")
		(33 "B.Fab" user "Ref Des/Assembly Bottom")
	)
	(footprint ""
		(layer "F.Cu")
		(at 450.43725 -45.314362 180)
		(property "Reference" "R3500"
			(at 0 0 180)
			(layer "F.SilkS")
			(hide yes)
			(effects
				(font
					(size 1.27 1.27)
				)
			)
		)
		(property "Value" ""
			(at 0 0 180)
			(layer "F.Fab")
			(effects
				(font
					(size 1.27 1.27)
				)
			)
		)
		(duplicate_pad_numbers_are_jumpers no)
		(fp_line
			(start 0.7874 0.4064)
			(end -0.7874 0.4064)
			(stroke
				(width 0.1524)
				(type default)
			)
			(layer "F.SilkS")
		)
		(fp_line
			(start 0.7874 -0.4064)
			(end 0.7874 0.4064)
			(stroke
				(width 0.1524)
				(type default)
			)
			(layer "F.SilkS")
		)
		(fp_line
			(start -0.7874 0.4064)
			(end -0.7874 -0.4064)
			(stroke
				(width 0.1524)
				(type default)
			)
			(layer "F.SilkS")
		)
		(fp_line
			(start -0.7874 -0.4064)
			(end 0.7874 -0.4064)
			(stroke
				(width 0.1524)
				(type default)
			)
			(layer "F.SilkS")
		)
		(fp_line
			(start 0.67945 0.3048)
			(end 0.120396 0.3048)
			(stroke
				(width 0.1)
				(type default)
			)
			(layer "F.Fab")
		)
		(fp_line
			(start 0.67945 -0.3048)
			(end 0.67945 0.3048)
			(stroke
				(width 0.1)
				(type default)
			)
			(layer "F.Fab")
		)
		(fp_line
			(start 0.12065 -0.2794)
			(end 0.12065 -0.3048)
			(stroke
				(width 0.1)
				(type default)
			)
			(layer "F.Fab")
		)
		(fp_line
			(start 0.12065 -0.3048)
			(end 0.67945 -0.3048)
			(stroke
				(width 0.1)
				(type default)
			)
			(layer "F.Fab")
		)
		(fp_line
			(start 0.120396 0.3048)
			(end 0.120396 0.2794)
			(stroke
				(width 0.1)
				(type default)
			)
			(layer "F.Fab")
		)
		(fp_line
			(start 0.120396 0.2794)
			(end -0.12065 0.2794)
			(stroke
				(width 0.1)
				(type default)
			)
			(layer "F.Fab")
		)
		(fp_line
			(start -0.12065 0.3048)
			(end -0.67945 0.3048)
			(stroke
				(width 0.1)
				(type default)
			)
			(layer "F.Fab")
		)
		(fp_line
			(start -0.12065 0.2794)
			(end -0.12065 0.3048)
			(stroke
				(width 0.1)
				(type default)
			)
			(layer "F.Fab")
		)
		(fp_line
			(start -0.12065 -0.2794)
			(end 0.12065 -0.2794)
			(stroke
				(width 0.1)
				(type default)
			)
			(layer "F.Fab")
		)
		(fp_line
			(start -0.12065 -0.305054)
			(end -0.12065 -0.2794)
			(stroke
				(width 0.1)
				(type default)
			)
			(layer "F.Fab")
		)
		(fp_line
			(start -0.67945 0.3048)
			(end -0.67945 -0.305054)
			(stroke
				(width 0.1)
				(type default)
			)
			(layer "F.Fab")
		)
		(fp_line
			(start -0.67945 -0.305054)
			(end -0.12065 -0.305054)
			(stroke
				(width 0.1)
				(type default)
			)
			(layer "F.Fab")
		)
		(pad "1" smd circle
			(at -0.40005 0 180)
			(size 0 0)
			(layers "F.Cu" "F.Mask" "F.Paste")
			(net "P3V3_OCP_SFF")
		)
		(pad "2" smd circle
			(at 0.40005 0 180)
			(size 0 0)
			(layers "F.Cu" "F.Mask" "F.Paste")
			(net "SMB_OCP_SFF_3V3AUX_BUF_SCL")
		)
	)
	(footprint ""
		(layer "F.Cu")
		(at 92.7354 -39.675308)
		(property "Reference" "C1820"
			(at 0 0 0)
			(layer "F.SilkS")
			(hide yes)
			(effects
				(font
					(size 1.27 1.27)
				)
			)
		)
		(property "Value" ""
			(at 0 0 0)
			(layer "F.Fab")
			(effects
				(font
					(size 1.27 1.27)
				)
			)
		)
		(duplicate_pad_numbers_are_jumpers no)
		(fp_line
			(start -0.7874 -0.4064)
			(end 0.7874 -0.4064)
			(stroke
				(width 0.1524)
				(type default)
			)
			(layer "F.SilkS")
		)
		(fp_line
			(start -0.7874 0.4064)
			(end -0.7874 -0.4064)
			(stroke
				(width 0.1524)
				(type default)
			)
			(layer "F.SilkS")
		)
		(fp_line
			(start 0.7874 -0.4064)
			(end 0.7874 0.4064)
			(stroke
				(width 0.1524)
				(type default)
			)
			(layer "F.SilkS")
		)
		(fp_line
			(start 0.7874 0.4064)
			(end -0.7874 0.4064)
			(stroke
				(width 0.1524)
				(type default)
			)
			(layer "F.SilkS")
		)
		(fp_line
			(start -0.67945 -0.305054)
			(end -0.12065 -0.305054)
			(stroke
				(width 0.1)
				(type default)
			)
			(layer "F.Fab")
		)
		(fp_line
			(start -0.67945 0.3048)
			(end -0.67945 -0.305054)
			(stroke
				(width 0.1)
				(type default)
			)
			(layer "F.Fab")
		)
		(fp_line
			(start -0.12065 -0.305054)
			(end -0.12065 -0.2794)
			(stroke
				(width 0.1)
				(type default)
			)
			(layer "F.Fab")
		)
		(fp_line
			(start -0.12065 -0.2794)
			(end 0.12065 -0.2794)
			(stroke
				(width 0.1)
				(type default)
			)
			(layer "F.Fab")
		)
		(fp_line
			(start -0.12065 0.2794)
			(end -0.12065 0.3048)
			(stroke
				(width 0.1)
				(type default)
			)
			(layer "F.Fab")
		)
		(fp_line
			(start -0.12065 0.3048)
			(end -0.67945 0.3048)
			(stroke
				(width 0.1)
				(type default)
			)
			(layer "F.Fab")
		)
		(fp_line
			(start 0.120396 0.2794)
			(end -0.12065 0.2794)
			(stroke
				(width 0.1)
				(type default)
			)
			(layer "F.Fab")
		)
		(fp_line
			(start 0.120396 0.3048)
			(end 0.120396 0.2794)
			(stroke
				(width 0.1)
				(type default)
			)
			(layer "F.Fab")
		)
		(fp_line
			(start 0.12065 -0.3048)
			(end 0.67945 -0.3048)
			(stroke
				(width 0.1)
				(type default)
			)
			(layer "F.Fab")
		)
		(fp_line
			(start 0.12065 -0.2794)
			(end 0.12065 -0.3048)
			(stroke
				(width 0.1)
				(type default)
			)
			(layer "F.Fab")
		)
		(fp_line
			(start 0.67945 -0.3048)
			(end 0.67945 0.3048)
			(stroke
				(width 0.1)
				(type default)
			)
			(layer "F.Fab")
		)
		(fp_line
			(start 0.67945 0.3048)
			(end 0.120396 0.3048)
			(stroke
				(width 0.1)
				(type default)
			)
			(layer "F.Fab")
		)
		(pad "1" smd circle
			(at -0.40005 0)
			(size 0 0)
			(layers "F.Cu" "F.Mask" "F.Paste")
			(net "P3V3_AUX")
		)
		(pad "2" smd circle
			(at 0.40005 0)
			(size 0 0)
			(layers "F.Cu" "F.Mask" "F.Paste")
			(net "GND")
		)
	)
	(footprint ""
		(layer "F.Cu")
		(at 258.375658 -49.558956)
		(property "Reference" "PC2196"
			(at 0 0 0)
			(layer "F.SilkS")
			(hide yes)
			(effects
				(font
					(size 1.27 1.27)
				)
			)
		)
		(property "Value" ""
			(at 0 0 0)
			(layer "F.Fab")
			(effects
				(font
					(size 1.27 1.27)
				)
			)
		)
		(duplicate_pad_numbers_are_jumpers no)
		(fp_line
			(start -0.7874 -0.4064)
			(end 0.7874 -0.4064)
			(stroke
				(width 0.1524)
				(type default)
			)
			(layer "F.SilkS")
		)
		(fp_line
			(start -0.7874 0.4064)
			(end -0.7874 -0.4064)
			(stroke
				(width 0.1524)
				(type default)
			)
			(layer "F.SilkS")
		)
		(fp_line
			(start 0.7874 -0.4064)
			(end 0.7874 0.4064)
			(stroke
				(width 0.1524)
				(type default)
			)
			(layer "F.SilkS")
		)
		(fp_line
			(start 0.7874 0.4064)
			(end -0.7874 0.4064)
			(stroke
				(width 0.1524)
				(type default)
			)
			(layer "F.SilkS")
		)
		(fp_line
			(start -0.67945 -0.305054)
			(end -0.12065 -0.305054)
			(stroke
				(width 0.1)
				(type default)
			)
			(layer "F.Fab")
		)
		(fp_line
			(start -0.67945 0.3048)
			(end -0.67945 -0.305054)
			(stroke
				(width 0.1)
				(type default)
			)
			(layer "F.Fab")
		)
		(fp_line
			(start -0.12065 -0.305054)
			(end -0.12065 -0.2794)
			(stroke
				(width 0.1)
				(type default)
			)
			(layer "F.Fab")
		)
		(fp_line
			(start -0.12065 -0.2794)
			(end 0.12065 -0.2794)
			(stroke
				(width 0.1)
				(type default)
			)
			(layer "F.Fab")
		)
		(fp_line
			(start -0.12065 0.2794)
			(end -0.12065 0.3048)
			(stroke
				(width 0.1)
				(type default)
			)
			(layer "F.Fab")
		)
		(fp_line
			(start -0.12065 0.3048)
			(end -0.67945 0.3048)
			(stroke
				(width 0.1)
				(type default)
			)
			(layer "F.Fab")
		)
		(fp_line
			(start 0.120396 0.2794)
			(end -0.12065 0.2794)
			(stroke
				(width 0.1)
				(type default)
			)
			(layer "F.Fab")
		)
		(fp_line
			(start 0.120396 0.3048)
			(end 0.120396 0.2794)
			(stroke
				(width 0.1)
				(type default)
			)
			(layer "F.Fab")
		)
		(fp_line
			(start 0.12065 -0.3048)
			(end 0.67945 -0.3048)
			(stroke
				(width 0.1)
				(type default)
			)
			(layer "F.Fab")
		)
		(fp_line
			(start 0.12065 -0.2794)
			(end 0.12065 -0.3048)
			(stroke
				(width 0.1)
				(type default)
			)
			(layer "F.Fab")
		)
		(fp_line
			(start 0.67945 -0.3048)
			(end 0.67945 0.3048)
			(stroke
				(width 0.1)
				(type default)
			)
			(layer "F.Fab")
		)
		(fp_line
			(start 0.67945 0.3048)
			(end 0.120396 0.3048)
			(stroke
				(width 0.1)
				(type default)
			)
			(layer "F.Fab")
		)
		(pad "1" smd circle
			(at -0.40005 0)
			(size 0 0)
			(layers "F.Cu" "F.Mask" "F.Paste")
			(net "P12V_E1S_TIMER_0")
		)
		(pad "2" smd circle
			(at 0.40005 0)
			(size 0 0)
			(layers "F.Cu" "F.Mask" "F.Paste")
			(net "GND")
		)
	)
	(footprint ""
		(layer "F.Cu")
		(at 444.715138 -71.898002 -90)
		(property "Reference" "PC581"
			(at 0 0 270)
			(layer "F.SilkS")
			(hide yes)
			(effects
				(font
					(size 1.27 1.27)
				)
			)
		)
		(property "Value" ""
			(at 0 0 270)
			(layer "F.Fab")
			(effects
				(font
					(size 1.27 1.27)
				)
			)
		)
		(duplicate_pad_numbers_are_jumpers no)
		(fp_line
			(start -1.2954 0.5842)
			(end -1.2954 -0.5842)
			(stroke
				(width 0.1524)
				(type default)
			)
			(layer "F.SilkS")
		)
		(fp_line
			(start 1.2954 0.5842)
			(end -1.2954 0.5842)
			(stroke
				(width 0.1524)
				(type default)
			)
			(layer "F.SilkS")
		)
		(fp_line
			(start -1.2954 -0.5842)
			(end 1.2954 -0.5842)
			(stroke
				(width 0.1524)
				(type default)
			)
			(layer "F.SilkS")
		)
		(fp_line
			(start 0 -0.5842)
			(end 0 0.5842)
			(stroke
				(width 0.1524)
				(type default)
			)
			(layer "F.SilkS")
		)
		(fp_line
			(start 1.2954 -0.5842)
			(end 1.2954 0.5842)
			(stroke
				(width 0.1524)
				(type default)
			)
			(layer "F.SilkS")
		)
		(fp_line
			(start -0.8636 0.4572)
			(end -0.8636 0.4064)
			(stroke
				(width 0.1)
				(type default)
			)
			(layer "F.Fab")
		)
		(fp_line
			(start 0.8636 0.4572)
			(end -0.8636 0.4572)
			(stroke
				(width 0.1)
				(type default)
			)
			(layer "F.Fab")
		)
		(fp_line
			(start -1.1938 0.4064)
			(end -1.1938 -0.4064)
			(stroke
				(width 0.1)
				(type default)
			)
			(layer "F.Fab")
		)
		(fp_line
			(start -0.8636 0.4064)
			(end -1.1938 0.4064)
			(stroke
				(width 0.1)
				(type default)
			)
			(layer "F.Fab")
		)
		(fp_line
			(start 0.8636 0.4064)
			(end 0.8636 0.4572)
			(stroke
				(width 0.1)
				(type default)
			)
			(layer "F.Fab")
		)
		(fp_line
			(start 1.1938 0.4064)
			(end 0.8636 0.4064)
			(stroke
				(width 0.1)
				(type default)
			)
			(layer "F.Fab")
		)
		(fp_line
			(start -1.1938 -0.4064)
			(end -0.8636 -0.4064)
			(stroke
				(width 0.1)
				(type default)
			)
			(layer "F.Fab")
		)
		(fp_line
			(start -0.8636 -0.4064)
			(end -0.8636 -0.4572)
			(stroke
				(width 0.1)
				(type default)
			)
			(layer "F.Fab")
		)
		(fp_line
			(start 0.8636 -0.4064)
			(end 1.1938 -0.4064)
			(stroke
				(width 0.1)
				(type default)
			)
			(layer "F.Fab")
		)
		(fp_line
			(start 1.1938 -0.4064)
			(end 1.1938 0.4064)
			(stroke
				(width 0.1)
				(type default)
			)
			(layer "F.Fab")
		)
		(fp_line
			(start -0.8636 -0.4572)
			(end 0.8636 -0.4572)
			(stroke
				(width 0.1)
				(type default)
			)
			(layer "F.Fab")
		)
		(fp_line
			(start 0.8636 -0.4572)
			(end 0.8636 -0.4064)
			(stroke
				(width 0.1)
				(type default)
			)
			(layer "F.Fab")
		)
		(pad "1" smd rect
			(at -0.7366 0 180)
			(size 0.7112 0.8128)
			(layers "F.Cu" "F.Mask" "F.Paste")
			(net "P3V3_AUX_VDRV")
		)
		(pad "2" smd rect
			(at 0.7366 0 180)
			(size 0.7112 0.8128)
			(layers "F.Cu" "F.Mask" "F.Paste")
			(net "GND")
		)
	)
	(footprint ""
		(layer "F.Cu")
		(at 54.811168 -151.411178)
		(property "Reference" "PC445_P1_2"
			(at 0 0 0)
			(layer "F.SilkS")
			(hide yes)
			(effects
				(font
					(size 1.27 1.27)
				)
			)
		)
		(property "Value" ""
			(at 0 0 0)
			(layer "F.Fab")
			(effects
				(font
					(size 1.27 1.27)
				)
			)
		)
		(duplicate_pad_numbers_are_jumpers no)
		(fp_line
			(start -0.7874 -0.4064)
			(end 0.7874 -0.4064)
			(stroke
				(width 0.1524)
				(type default)
			)
			(layer "F.SilkS")
		)
		(fp_line
			(start -0.7874 0.4064)
			(end -0.7874 -0.4064)
			(stroke
				(width 0.1524)
				(type default)
			)
			(layer "F.SilkS")
		)
		(fp_line
			(start 0.7874 -0.4064)
			(end 0.7874 0.4064)
			(stroke
				(width 0.1524)
				(type default)
			)
			(layer "F.SilkS")
		)
		(fp_line
			(start 0.7874 0.4064)
			(end -0.7874 0.4064)
			(stroke
				(width 0.1524)
				(type default)
			)
			(layer "F.SilkS")
		)
		(fp_line
			(start -0.67945 -0.305054)
			(end -0.12065 -0.305054)
			(stroke
				(width 0.1)
				(type default)
			)
			(layer "F.Fab")
		)
		(fp_line
			(start -0.67945 0.3048)
			(end -0.67945 -0.305054)
			(stroke
				(width 0.1)
				(type default)
			)
			(layer "F.Fab")
		)
		(fp_line
			(start -0.12065 -0.305054)
			(end -0.12065 -0.2794)
			(stroke
				(width 0.1)
				(type default)
			)
			(layer "F.Fab")
		)
		(fp_line
			(start -0.12065 -0.2794)
			(end 0.12065 -0.2794)
			(stroke
				(width 0.1)
				(type default)
			)
			(layer "F.Fab")
		)
		(fp_line
			(start -0.12065 0.2794)
			(end -0.12065 0.3048)
			(stroke
				(width 0.1)
				(type default)
			)
			(layer "F.Fab")
		)
		(fp_line
			(start -0.12065 0.3048)
			(end -0.67945 0.3048)
			(stroke
				(width 0.1)
				(type default)
			)
			(layer "F.Fab")
		)
		(fp_line
			(start 0.120396 0.2794)
			(end -0.12065 0.2794)
			(stroke
				(width 0.1)
				(type default)
			)
			(layer "F.Fab")
		)
		(fp_line
			(start 0.120396 0.3048)
			(end 0.120396 0.2794)
			(stroke
				(width 0.1)
				(type default)
			)
			(layer "F.Fab")
		)
		(fp_line
			(start 0.12065 -0.3048)
			(end 0.67945 -0.3048)
			(stroke
				(width 0.1)
				(type default)
			)
			(layer "F.Fab")
		)
		(fp_line
			(start 0.12065 -0.2794)
			(end 0.12065 -0.3048)
			(stroke
				(width 0.1)
				(type default)
			)
			(layer "F.Fab")
		)
		(fp_line
			(start 0.67945 -0.3048)
			(end 0.67945 0.3048)
			(stroke
				(width 0.1)
				(type default)
			)
			(layer "F.Fab")
		)
		(fp_line
			(start 0.67945 0.3048)
			(end 0.120396 0.3048)
			(stroke
				(width 0.1)
				(type default)
			)
			(layer "F.Fab")
		)
		(pad "1" smd circle
			(at -0.40005 0)
			(size 0 0)
			(layers "F.Cu" "F.Mask" "F.Paste")
			(net "SW_P12V_PVCCINFAON_CPU1_FLT")
		)
		(pad "2" smd circle
			(at 0.40005 0)
			(size 0 0)
			(layers "F.Cu" "F.Mask" "F.Paste")
			(net "GND")
		)
	)
	(footprint ""
		(layer "F.Cu")
		(at 306.215288 -408.517344 -90)
		(property "Reference" "C903"
			(at 0 0 270)
			(layer "F.SilkS")
			(hide yes)
			(effects
				(font
					(size 1.27 1.27)
				)
			)
		)
		(property "Value" ""
			(at 0 0 270)
			(layer "F.Fab")
			(effects
				(font
					(size 1.27 1.27)
				)
			)
		)
		(duplicate_pad_numbers_are_jumpers no)
		(fp_line
			(start -0.299974 0.150114)
			(end -0.299974 -0.150114)
			(stroke
				(width 0.1)
				(type default)
			)
			(layer "F.Fab")
		)
		(fp_line
			(start 0.299974 0.150114)
			(end -0.299974 0.150114)
			(stroke
				(width 0.1)
				(type default)
			)
			(layer "F.Fab")
		)
		(fp_line
			(start -0.299974 -0.150114)
			(end 0.299974 -0.150114)
			(stroke
				(width 0.1)
				(type default)
			)
			(layer "F.Fab")
		)
		(fp_line
			(start 0.299974 -0.150114)
			(end 0.299974 0.150114)
			(stroke
				(width 0.1)
				(type default)
			)
			(layer "F.Fab")
		)
		(pad "1" smd rect
			(at -0.2667 0 270)
			(size 0.3048 0.381)
			(layers "F.Cu" "F.Mask" "F.Paste")
			(net "P5E_CPU0_PE0_TX_C_DP<15>")
		)
		(pad "2" smd rect
			(at 0.2667 0 270)
			(size 0.3048 0.381)
			(layers "F.Cu" "F.Mask" "F.Paste")
			(net "P5E_CPU0_PE0_TX_DP<15>")
		)
	)
	(footprint ""
		(layer "F.Cu")
		(at 325.077836 -345.462606 90)
		(property "Reference" "PC227"
			(at 0 0 90)
			(layer "F.SilkS")
			(hide yes)
			(effects
				(font
					(size 1.27 1.27)
				)
			)
		)
		(property "Value" ""
			(at 0 0 90)
			(layer "F.Fab")
			(effects
				(font
					(size 1.27 1.27)
				)
			)
		)
		(duplicate_pad_numbers_are_jumpers no)
		(fp_line
			(start 0.7874 -0.4064)
			(end 0.7874 0.4064)
			(stroke
				(width 0.1524)
				(type default)
			)
			(layer "F.SilkS")
		)
		(fp_line
			(start -0.7874 -0.4064)
			(end 0.7874 -0.4064)
			(stroke
				(width 0.1524)
				(type default)
			)
			(layer "F.SilkS")
		)
		(fp_line
			(start 0.7874 0.4064)
			(end -0.7874 0.4064)
			(stroke
				(width 0.1524)
				(type default)
			)
			(layer "F.SilkS")
		)
		(fp_line
			(start -0.7874 0.4064)
			(end -0.7874 -0.4064)
			(stroke
				(width 0.1524)
				(type default)
			)
			(layer "F.SilkS")
		)
		(fp_line
			(start -0.12065 -0.305054)
			(end -0.12065 -0.2794)
			(stroke
				(width 0.1)
				(type default)
			)
			(layer "F.Fab")
		)
		(fp_line
			(start -0.67945 -0.305054)
			(end -0.12065 -0.305054)
			(stroke
				(width 0.1)
				(type default)
			)
			(layer "F.Fab")
		)
		(fp_line
			(start 0.67945 -0.3048)
			(end 0.67945 0.3048)
			(stroke
				(width 0.1)
				(type default)
			)
			(layer "F.Fab")
		)
		(fp_line
			(start 0.12065 -0.3048)
			(end 0.67945 -0.3048)
			(stroke
				(width 0.1)
				(type default)
			)
			(layer "F.Fab")
		)
		(fp_line
			(start 0.12065 -0.2794)
			(end 0.12065 -0.3048)
			(stroke
				(width 0.1)
				(type default)
			)
			(layer "F.Fab")
		)
		(fp_line
			(start -0.12065 -0.2794)
			(end 0.12065 -0.2794)
			(stroke
				(width 0.1)
				(type default)
			)
			(layer "F.Fab")
		)
		(fp_line
			(start 0.120396 0.2794)
			(end -0.12065 0.2794)
			(stroke
				(width 0.1)
				(type default)
			)
			(layer "F.Fab")
		)
		(fp_line
			(start -0.12065 0.2794)
			(end -0.12065 0.3048)
			(stroke
				(width 0.1)
				(type default)
			)
			(layer "F.Fab")
		)
		(fp_line
			(start 0.67945 0.3048)
			(end 0.120396 0.3048)
			(stroke
				(width 0.1)
				(type default)
			)
			(layer "F.Fab")
		)
		(fp_line
			(start 0.120396 0.3048)
			(end 0.120396 0.2794)
			(stroke
				(width 0.1)
				(type default)
			)
			(layer "F.Fab")
		)
		(fp_line
			(start -0.12065 0.3048)
			(end -0.67945 0.3048)
			(stroke
				(width 0.1)
				(type default)
			)
			(layer "F.Fab")
		)
		(fp_line
			(start -0.67945 0.3048)
			(end -0.67945 -0.305054)
			(stroke
				(width 0.1)
				(type default)
			)
			(layer "F.Fab")
		)
		(pad "1" smd circle
			(at -0.40005 0 90)
			(size 0 0)
			(layers "F.Cu" "F.Mask" "F.Paste")
			(net "PVCCIN_CPU0_VDD7")
		)
		(pad "2" smd circle
			(at 0.40005 0 90)
			(size 0 0)
			(layers "F.Cu" "F.Mask" "F.Paste")
			(net "GND")
		)
	)
)
